(kicad_pcb
	(version 20260206)
	(generator "pcbnew")
	(generator_version "10.0")
	(general
		(thickness 1.6)
		(legacy_teardrops no)
	)
	(paper "A4")
	(title_block
		(title "04192023_DAF0TMB3IC0_F0TG_MB_C_brd_V02_OCP.brd")
		(comment 1 "Grand Teton / footprints 4797-4804 of 8354")
	)
	(layers
		(0 "F.Cu" signal "TOP")
		(4 "In1.Cu" signal "GND")
		(6 "In2.Cu" signal "IN1")
		(8 "In3.Cu" signal "GND1")
		(10 "In4.Cu" signal "IN2")
		(12 "In5.Cu" signal "GND2")
		(14 "In6.Cu" signal "IN3")
		(16 "In7.Cu" signal "GND3")
		(18 "In8.Cu" signal "VCC")
		(20 "In9.Cu" signal "VCC1")
		(22 "In10.Cu" signal "GND4")
		(24 "In11.Cu" signal "IN4")
		(26 "In12.Cu" signal "GND5")
		(28 "In13.Cu" signal "IN5")
		(30 "In14.Cu" signal "GND6")
		(32 "In15.Cu" signal "IN6")
		(34 "In16.Cu" signal "GND7")
		(2 "B.Cu" signal "BOTTOM")
		(9 "F.Adhes" user "F.Adhesive")
		(11 "B.Adhes" user "B.Adhesive")
		(13 "F.Paste" user "Package Geometry/Pastemask Top")
		(15 "B.Paste" user "Package Geometry/Pastemask Bottom")
		(5 "F.SilkS" user "Ref Des/Silkscreen Top")
		(7 "B.SilkS" user "Ref Des/Silkscreen Bottom")
		(1 "F.Mask" user "Board Geometry/Soldermask Top")
		(3 "B.Mask" user "Board Geometry/Soldermask Bottom")
		(17 "Dwgs.User" user "User.Drawings")
		(19 "Cmts.User" user "User.Comments")
		(21 "Eco1.User" user "User.Eco1")
		(23 "Eco2.User" user "User.Eco2")
		(25 "Edge.Cuts" user "Board Geometry/Outline")
		(27 "Margin" user)
		(31 "F.CrtYd" user "Package Geometry/Place Bound Top")
		(29 "B.CrtYd" user "Package Geometry/Place Bound Bottom")
		(35 "F.Fab" user "Ref Des/Assembly Top")
		(33 "B.Fab" user "Ref Des/Assembly Bottom")
	)
	(footprint ""
		(layer "F.Cu")
		(at 224.074482 -57.386982 90)
		(property "Reference" "R3767"
			(at 4.689348 -1.951482 0)
			(unlocked yes)
			(layer "F.SilkS")
			(effects
				(font
					(size 0.7874 0.5842)
					(thickness 0.1524)
				)
				(justify left)
			)
		)
		(property "Value" ""
			(at 0 0 90)
			(layer "F.Fab")
			(effects
				(font
					(size 1.27 1.27)
				)
			)
		)
		(duplicate_pad_numbers_are_jumpers no)
		(fp_line
			(start 3.937508 -1.8796)
			(end -3.937508 -1.8796)
			(stroke
				(width 0.1524)
				(type default)
			)
			(layer "F.SilkS")
		)
		(fp_line
			(start -3.937508 -1.8796)
			(end -3.937508 1.8796)
			(stroke
				(width 0.1524)
				(type default)
			)
			(layer "F.SilkS")
		)
		(fp_line
			(start 3.937508 1.8796)
			(end 3.937508 -1.8796)
			(stroke
				(width 0.1524)
				(type default)
			)
			(layer "F.SilkS")
		)
		(fp_line
			(start -3.937508 1.8796)
			(end 3.937508 1.8796)
			(stroke
				(width 0.1524)
				(type default)
			)
			(layer "F.SilkS")
		)
		(fp_line
			(start 3.275076 -1.674876)
			(end -3.275076 -1.674876)
			(stroke
				(width 0.1)
				(type default)
			)
			(layer "F.Fab")
		)
		(fp_line
			(start -3.275076 -1.674876)
			(end -3.275076 1.674876)
			(stroke
				(width 0.1)
				(type default)
			)
			(layer "F.Fab")
		)
		(fp_line
			(start 3.275076 1.674876)
			(end 3.275076 -1.674876)
			(stroke
				(width 0.1)
				(type default)
			)
			(layer "F.Fab")
		)
		(fp_line
			(start -3.275076 1.674876)
			(end 3.275076 1.674876)
			(stroke
				(width 0.1)
				(type default)
			)
			(layer "F.Fab")
		)
		(pad "1" smd rect
			(at -2.350008 0 90)
			(size 2.921 3.5052)
			(layers "F.Cu" "F.Mask" "F.Paste")
			(net "P3V3_E1S_0")
		)
		(pad "2" smd rect
			(at 2.350008 0 90)
			(size 2.921 3.5052)
			(layers "F.Cu" "F.Mask" "F.Paste")
			(net "P3V3_E1S_0_R")
		)
	)
	(footprint ""
		(layer "F.Cu")
		(at 448.271392 -47.506382 -90)
		(property "Reference" "PC576"
			(at 0 0 270)
			(layer "F.SilkS")
			(hide yes)
			(effects
				(font
					(size 1.27 1.27)
				)
			)
		)
		(property "Value" ""
			(at 0 0 270)
			(layer "F.Fab")
			(effects
				(font
					(size 1.27 1.27)
				)
			)
		)
		(duplicate_pad_numbers_are_jumpers no)
		(fp_line
			(start -1.524 0.762)
			(end -1.524 -0.762)
			(stroke
				(width 0.1524)
				(type default)
			)
			(layer "F.SilkS")
		)
		(fp_line
			(start 1.524 0.762)
			(end -1.524 0.762)
			(stroke
				(width 0.1524)
				(type default)
			)
			(layer "F.SilkS")
		)
		(fp_line
			(start -1.524 -0.762)
			(end 1.524 -0.762)
			(stroke
				(width 0.1524)
				(type default)
			)
			(layer "F.SilkS")
		)
		(fp_line
			(start 1.524 -0.762)
			(end 1.524 0.762)
			(stroke
				(width 0.1524)
				(type default)
			)
			(layer "F.SilkS")
		)
		(fp_line
			(start -1.1049 0.724916)
			(end 1.1049 0.724916)
			(stroke
				(width 0.1)
				(type default)
			)
			(layer "F.Fab")
		)
		(fp_line
			(start 1.1049 0.724916)
			(end 1.1049 -0.724916)
			(stroke
				(width 0.1)
				(type default)
			)
			(layer "F.Fab")
		)
		(fp_line
			(start -1.1049 -0.724916)
			(end -1.1049 0.724916)
			(stroke
				(width 0.1)
				(type default)
			)
			(layer "F.Fab")
		)
		(fp_line
			(start 1.1049 -0.724916)
			(end -1.1049 -0.724916)
			(stroke
				(width 0.1)
				(type default)
			)
			(layer "F.Fab")
		)
		(pad "1" smd rect
			(at -0.889 0 90)
			(size 1.016 1.27)
			(layers "F.Cu" "F.Mask" "F.Paste")
			(net "SW_P3V3_AUX_FLT")
		)
		(pad "2" smd rect
			(at 0.889 0 90)
			(size 1.016 1.27)
			(layers "F.Cu" "F.Mask" "F.Paste")
			(net "GND")
		)
	)
	(footprint ""
		(layer "F.Cu")
		(at 441.951872 -351.415858)
		(property "Reference" "H34"
			(at -1.7272 -4.177792 0)
			(unlocked yes)
			(layer "F.SilkS")
			(effects
				(font
					(size 0.7874 0.5842)
					(thickness 0.1524)
				)
				(justify left)
			)
		)
		(property "Value" ""
			(at 0 0 0)
			(layer "F.Fab")
			(effects
				(font
					(size 1.27 1.27)
				)
			)
		)
		(duplicate_pad_numbers_are_jumpers no)
		(pad "1" thru_hole circle
			(at 0 0)
			(size 6.1976 6.1976)
			(drill 3.7338)
			(layers "*.Cu" "*.Mask")
			(remove_unused_layers no)
			(net "GND")
			(clearance -0.9779)
			(padstack
				(mode front_inner_back)
				(layer "Inner"
					(shape circle)
					(size 5.5372 5.5372)
					(clearance -0.6477)
				)
				(layer "B.Cu"
					(shape circle)
					(size 6.1976 6.1976)
					(clearance -0.9779)
				)
			)
		)
	)
	(footprint ""
		(layer "F.Cu")
		(at 308.420516 -437.498744 -90)
		(property "Reference" "R4134"
			(at 0 0 270)
			(layer "F.SilkS")
			(hide yes)
			(effects
				(font
					(size 1.27 1.27)
				)
			)
		)
		(property "Value" ""
			(at 0 0 270)
			(layer "F.Fab")
			(effects
				(font
					(size 1.27 1.27)
				)
			)
		)
		(duplicate_pad_numbers_are_jumpers no)
		(fp_line
			(start -0.7874 0.4064)
			(end -0.7874 -0.4064)
			(stroke
				(width 0.1524)
				(type default)
			)
			(layer "F.SilkS")
		)
		(fp_line
			(start 0.7874 0.4064)
			(end -0.7874 0.4064)
			(stroke
				(width 0.1524)
				(type default)
			)
			(layer "F.SilkS")
		)
		(fp_line
			(start -0.7874 -0.4064)
			(end 0.7874 -0.4064)
			(stroke
				(width 0.1524)
				(type default)
			)
			(layer "F.SilkS")
		)
		(fp_line
			(start 0.7874 -0.4064)
			(end 0.7874 0.4064)
			(stroke
				(width 0.1524)
				(type default)
			)
			(layer "F.SilkS")
		)
		(fp_line
			(start -0.67945 0.3048)
			(end -0.67945 -0.305054)
			(stroke
				(width 0.1)
				(type default)
			)
			(layer "F.Fab")
		)
		(fp_line
			(start -0.12065 0.3048)
			(end -0.67945 0.3048)
			(stroke
				(width 0.1)
				(type default)
			)
			(layer "F.Fab")
		)
		(fp_line
			(start 0.120396 0.3048)
			(end 0.120396 0.2794)
			(stroke
				(width 0.1)
				(type default)
			)
			(layer "F.Fab")
		)
		(fp_line
			(start 0.67945 0.3048)
			(end 0.120396 0.3048)
			(stroke
				(width 0.1)
				(type default)
			)
			(layer "F.Fab")
		)
		(fp_line
			(start -0.12065 0.2794)
			(end -0.12065 0.3048)
			(stroke
				(width 0.1)
				(type default)
			)
			(layer "F.Fab")
		)
		(fp_line
			(start 0.120396 0.2794)
			(end -0.12065 0.2794)
			(stroke
				(width 0.1)
				(type default)
			)
			(layer "F.Fab")
		)
		(fp_line
			(start -0.12065 -0.2794)
			(end 0.12065 -0.2794)
			(stroke
				(width 0.1)
				(type default)
			)
			(layer "F.Fab")
		)
		(fp_line
			(start 0.12065 -0.2794)
			(end 0.12065 -0.3048)
			(stroke
				(width 0.1)
				(type default)
			)
			(layer "F.Fab")
		)
		(fp_line
			(start 0.12065 -0.3048)
			(end 0.67945 -0.3048)
			(stroke
				(width 0.1)
				(type default)
			)
			(layer "F.Fab")
		)
		(fp_line
			(start 0.67945 -0.3048)
			(end 0.67945 0.3048)
			(stroke
				(width 0.1)
				(type default)
			)
			(layer "F.Fab")
		)
		(fp_line
			(start -0.67945 -0.305054)
			(end -0.12065 -0.305054)
			(stroke
				(width 0.1)
				(type default)
			)
			(layer "F.Fab")
		)
		(fp_line
			(start -0.12065 -0.305054)
			(end -0.12065 -0.2794)
			(stroke
				(width 0.1)
				(type default)
			)
			(layer "F.Fab")
		)
		(pad "1" smd circle
			(at -0.40005 0 270)
			(size 0 0)
			(layers "F.Cu" "F.Mask" "F.Paste")
			(net "GPU_3V3IO_RSVD5_FFU")
		)
		(pad "2" smd circle
			(at 0.40005 0 270)
			(size 0 0)
			(layers "F.Cu" "F.Mask" "F.Paste")
			(net "GND")
		)
	)
	(footprint ""
		(layer "F.Cu")
		(at 363.793278 -171.64431)
		(property "Reference" "PC479_1"
			(at 0 0 0)
			(layer "F.SilkS")
			(hide yes)
			(effects
				(font
					(size 1.27 1.27)
				)
			)
		)
		(property "Value" ""
			(at 0 0 0)
			(layer "F.Fab")
			(effects
				(font
					(size 1.27 1.27)
				)
			)
		)
		(duplicate_pad_numbers_are_jumpers no)
		(fp_line
			(start -0.7874 -0.4064)
			(end 0.7874 -0.4064)
			(stroke
				(width 0.1524)
				(type default)
			)
			(layer "F.SilkS")
		)
		(fp_line
			(start -0.7874 0.4064)
			(end -0.7874 -0.4064)
			(stroke
				(width 0.1524)
				(type default)
			)
			(layer "F.SilkS")
		)
		(fp_line
			(start 0.7874 -0.4064)
			(end 0.7874 0.4064)
			(stroke
				(width 0.1524)
				(type default)
			)
			(layer "F.SilkS")
		)
		(fp_line
			(start 0.7874 0.4064)
			(end -0.7874 0.4064)
			(stroke
				(width 0.1524)
				(type default)
			)
			(layer "F.SilkS")
		)
		(fp_line
			(start -0.67945 -0.305054)
			(end -0.12065 -0.305054)
			(stroke
				(width 0.1)
				(type default)
			)
			(layer "F.Fab")
		)
		(fp_line
			(start -0.67945 0.3048)
			(end -0.67945 -0.305054)
			(stroke
				(width 0.1)
				(type default)
			)
			(layer "F.Fab")
		)
		(fp_line
			(start -0.12065 -0.305054)
			(end -0.12065 -0.2794)
			(stroke
				(width 0.1)
				(type default)
			)
			(layer "F.Fab")
		)
		(fp_line
			(start -0.12065 -0.2794)
			(end 0.12065 -0.2794)
			(stroke
				(width 0.1)
				(type default)
			)
			(layer "F.Fab")
		)
		(fp_line
			(start -0.12065 0.2794)
			(end -0.12065 0.3048)
			(stroke
				(width 0.1)
				(type default)
			)
			(layer "F.Fab")
		)
		(fp_line
			(start -0.12065 0.3048)
			(end -0.67945 0.3048)
			(stroke
				(width 0.1)
				(type default)
			)
			(layer "F.Fab")
		)
		(fp_line
			(start 0.120396 0.2794)
			(end -0.12065 0.2794)
			(stroke
				(width 0.1)
				(type default)
			)
			(layer "F.Fab")
		)
		(fp_line
			(start 0.120396 0.3048)
			(end 0.120396 0.2794)
			(stroke
				(width 0.1)
				(type default)
			)
			(layer "F.Fab")
		)
		(fp_line
			(start 0.12065 -0.3048)
			(end 0.67945 -0.3048)
			(stroke
				(width 0.1)
				(type default)
			)
			(layer "F.Fab")
		)
		(fp_line
			(start 0.12065 -0.2794)
			(end 0.12065 -0.3048)
			(stroke
				(width 0.1)
				(type default)
			)
			(layer "F.Fab")
		)
		(fp_line
			(start 0.67945 -0.3048)
			(end 0.67945 0.3048)
			(stroke
				(width 0.1)
				(type default)
			)
			(layer "F.Fab")
		)
		(fp_line
			(start 0.67945 0.3048)
			(end 0.120396 0.3048)
			(stroke
				(width 0.1)
				(type default)
			)
			(layer "F.Fab")
		)
		(pad "1" smd circle
			(at -0.40005 0)
			(size 0 0)
			(layers "F.Cu" "F.Mask" "F.Paste")
			(net "SW_P12V_AUX_PVDDCR_CPU0_P0_FLT")
		)
		(pad "2" smd circle
			(at 0.40005 0)
			(size 0 0)
			(layers "F.Cu" "F.Mask" "F.Paste")
			(net "GND")
		)
	)
	(footprint ""
		(layer "F.Cu")
		(at 126.58979 -27.863546 -90)
		(property "Reference" "C91"
			(at 0 0 270)
			(layer "F.SilkS")
			(hide yes)
			(effects
				(font
					(size 1.27 1.27)
				)
			)
		)
		(property "Value" ""
			(at 0 0 270)
			(layer "F.Fab")
			(effects
				(font
					(size 1.27 1.27)
				)
			)
		)
		(duplicate_pad_numbers_are_jumpers no)
		(fp_line
			(start -0.7874 0.4064)
			(end -0.7874 -0.4064)
			(stroke
				(width 0.1524)
				(type default)
			)
			(layer "F.SilkS")
		)
		(fp_line
			(start 0.7874 0.4064)
			(end -0.7874 0.4064)
			(stroke
				(width 0.1524)
				(type default)
			)
			(layer "F.SilkS")
		)
		(fp_line
			(start -0.7874 -0.4064)
			(end 0.7874 -0.4064)
			(stroke
				(width 0.1524)
				(type default)
			)
			(layer "F.SilkS")
		)
		(fp_line
			(start 0.7874 -0.4064)
			(end 0.7874 0.4064)
			(stroke
				(width 0.1524)
				(type default)
			)
			(layer "F.SilkS")
		)
		(fp_line
			(start -0.67945 0.3048)
			(end -0.67945 -0.305054)
			(stroke
				(width 0.1)
				(type default)
			)
			(layer "F.Fab")
		)
		(fp_line
			(start -0.12065 0.3048)
			(end -0.67945 0.3048)
			(stroke
				(width 0.1)
				(type default)
			)
			(layer "F.Fab")
		)
		(fp_line
			(start 0.120396 0.3048)
			(end 0.120396 0.2794)
			(stroke
				(width 0.1)
				(type default)
			)
			(layer "F.Fab")
		)
		(fp_line
			(start 0.67945 0.3048)
			(end 0.120396 0.3048)
			(stroke
				(width 0.1)
				(type default)
			)
			(layer "F.Fab")
		)
		(fp_line
			(start -0.12065 0.2794)
			(end -0.12065 0.3048)
			(stroke
				(width 0.1)
				(type default)
			)
			(layer "F.Fab")
		)
		(fp_line
			(start 0.120396 0.2794)
			(end -0.12065 0.2794)
			(stroke
				(width 0.1)
				(type default)
			)
			(layer "F.Fab")
		)
		(fp_line
			(start -0.12065 -0.2794)
			(end 0.12065 -0.2794)
			(stroke
				(width 0.1)
				(type default)
			)
			(layer "F.Fab")
		)
		(fp_line
			(start 0.12065 -0.2794)
			(end 0.12065 -0.3048)
			(stroke
				(width 0.1)
				(type default)
			)
			(layer "F.Fab")
		)
		(fp_line
			(start 0.12065 -0.3048)
			(end 0.67945 -0.3048)
			(stroke
				(width 0.1)
				(type default)
			)
			(layer "F.Fab")
		)
		(fp_line
			(start 0.67945 -0.3048)
			(end 0.67945 0.3048)
			(stroke
				(width 0.1)
				(type default)
			)
			(layer "F.Fab")
		)
		(fp_line
			(start -0.67945 -0.305054)
			(end -0.12065 -0.305054)
			(stroke
				(width 0.1)
				(type default)
			)
			(layer "F.Fab")
		)
		(fp_line
			(start -0.12065 -0.305054)
			(end -0.12065 -0.2794)
			(stroke
				(width 0.1)
				(type default)
			)
			(layer "F.Fab")
		)
		(pad "1" smd circle
			(at -0.40005 0 270)
			(size 0 0)
			(layers "F.Cu" "F.Mask" "F.Paste")
			(net "XTAL_USB_CPU0_HUB1_XIN")
		)
		(pad "2" smd circle
			(at 0.40005 0 270)
			(size 0 0)
			(layers "F.Cu" "F.Mask" "F.Paste")
			(net "GND")
		)
	)
	(footprint ""
		(layer "F.Cu")
		(at 163.4236 -438.912)
		(property "Reference" "R2920"
			(at 0 0 0)
			(layer "F.SilkS")
			(hide yes)
			(effects
				(font
					(size 1.27 1.27)
				)
			)
		)
		(property "Value" ""
			(at 0 0 0)
			(layer "F.Fab")
			(effects
				(font
					(size 1.27 1.27)
				)
			)
		)
		(duplicate_pad_numbers_are_jumpers no)
		(fp_line
			(start -0.7874 -0.4064)
			(end 0.7874 -0.4064)
			(stroke
				(width 0.1524)
				(type default)
			)
			(layer "F.SilkS")
		)
		(fp_line
			(start -0.7874 0.4064)
			(end -0.7874 -0.4064)
			(stroke
				(width 0.1524)
				(type default)
			)
			(layer "F.SilkS")
		)
		(fp_line
			(start 0.7874 -0.4064)
			(end 0.7874 0.4064)
			(stroke
				(width 0.1524)
				(type default)
			)
			(layer "F.SilkS")
		)
		(fp_line
			(start 0.7874 0.4064)
			(end -0.7874 0.4064)
			(stroke
				(width 0.1524)
				(type default)
			)
			(layer "F.SilkS")
		)
		(fp_line
			(start -0.67945 -0.305054)
			(end -0.12065 -0.305054)
			(stroke
				(width 0.1)
				(type default)
			)
			(layer "F.Fab")
		)
		(fp_line
			(start -0.67945 0.3048)
			(end -0.67945 -0.305054)
			(stroke
				(width 0.1)
				(type default)
			)
			(layer "F.Fab")
		)
		(fp_line
			(start -0.12065 -0.305054)
			(end -0.12065 -0.2794)
			(stroke
				(width 0.1)
				(type default)
			)
			(layer "F.Fab")
		)
		(fp_line
			(start -0.12065 -0.2794)
			(end 0.12065 -0.2794)
			(stroke
				(width 0.1)
				(type default)
			)
			(layer "F.Fab")
		)
		(fp_line
			(start -0.12065 0.2794)
			(end -0.12065 0.3048)
			(stroke
				(width 0.1)
				(type default)
			)
			(layer "F.Fab")
		)
		(fp_line
			(start -0.12065 0.3048)
			(end -0.67945 0.3048)
			(stroke
				(width 0.1)
				(type default)
			)
			(layer "F.Fab")
		)
		(fp_line
			(start 0.120396 0.2794)
			(end -0.12065 0.2794)
			(stroke
				(width 0.1)
				(type default)
			)
			(layer "F.Fab")
		)
		(fp_line
			(start 0.120396 0.3048)
			(end 0.120396 0.2794)
			(stroke
				(width 0.1)
				(type default)
			)
			(layer "F.Fab")
		)
		(fp_line
			(start 0.12065 -0.3048)
			(end 0.67945 -0.3048)
			(stroke
				(width 0.1)
				(type default)
			)
			(layer "F.Fab")
		)
		(fp_line
			(start 0.12065 -0.2794)
			(end 0.12065 -0.3048)
			(stroke
				(width 0.1)
				(type default)
			)
			(layer "F.Fab")
		)
		(fp_line
			(start 0.67945 -0.3048)
			(end 0.67945 0.3048)
			(stroke
				(width 0.1)
				(type default)
			)
			(layer "F.Fab")
		)
		(fp_line
			(start 0.67945 0.3048)
			(end 0.120396 0.3048)
			(stroke
				(width 0.1)
				(type default)
			)
			(layer "F.Fab")
		)
		(pad "1" smd circle
			(at -0.40005 0)
			(size 0 0)
			(layers "F.Cu" "F.Mask" "F.Paste")
			(net "P3V3_AUX")
		)
		(pad "2" smd circle
			(at 0.40005 0)
			(size 0 0)
			(layers "F.Cu" "F.Mask" "F.Paste")
			(net "BIC_MONITER_ISO")
		)
	)
	(footprint ""
		(layer "F.Cu")
		(at 425.79163 -389.802116 -90)
		(property "Reference" "R1404"
			(at 0 0 270)
			(layer "F.SilkS")
			(hide yes)
			(effects
				(font
					(size 1.27 1.27)
				)
			)
		)
		(property "Value" ""
			(at 0 0 270)
			(layer "F.Fab")
			(effects
				(font
					(size 1.27 1.27)
				)
			)
		)
		(duplicate_pad_numbers_are_jumpers no)
		(fp_line
			(start -0.32512 0.175006)
			(end -0.32512 -0.175006)
			(stroke
				(width 0.1)
				(type default)
			)
			(layer "F.Fab")
		)
		(fp_line
			(start 0.32512 0.175006)
			(end -0.32512 0.175006)
			(stroke
				(width 0.1)
				(type default)
			)
			(layer "F.Fab")
		)
		(fp_line
			(start -0.32512 -0.175006)
			(end 0.32512 -0.175006)
			(stroke
				(width 0.1)
				(type default)
			)
			(layer "F.Fab")
		)
		(fp_line
			(start 0.32512 -0.175006)
			(end 0.32512 0.175006)
			(stroke
				(width 0.1)
				(type default)
			)
			(layer "F.Fab")
		)
		(pad "1" smd rect
			(at -0.2667 0 270)
			(size 0.3048 0.381)
			(layers "F.Cu" "F.Mask" "F.Paste")
			(net "CLKREQ_RT_CPU0_P2_N")
		)
		(pad "2" smd rect
			(at 0.2667 0 90)
			(size 0.3048 0.381)
			(layers "F.Cu" "F.Mask" "F.Paste")
			(net "GND")
		)
	)
)
